(kicad_pcb
	(version 20241229)
	(generator "pcbnew")
	(generator_version "9.0")
	(general
		(thickness 1.63)
		(legacy_teardrops no)
	)
	(paper "A4")
	(title_block
		(title "CM4 Baseboard")
		(date "2026-01-05")
		(rev "1.1.1")
		(company "Antmicro Ltd")
		(comment 1 "www.antmicro.com")
		(comment 9 "footprints 220-224 of 506")
	)
	(layers
		(0 "F.Cu" signal)
		(4 "In1.Cu" power)
		(6 "In2.Cu" power)
		(8 "In3.Cu" signal)
		(10 "In4.Cu" signal)
		(2 "B.Cu" signal)
		(9 "F.Adhes" user "F.Adhesive")
		(11 "B.Adhes" user "B.Adhesive")
		(13 "F.Paste" user)
		(15 "B.Paste" user)
		(5 "F.SilkS" user "F.Silkscreen")
		(7 "B.SilkS" user "B.Silkscreen")
		(1 "F.Mask" user)
		(3 "B.Mask" user)
		(17 "Dwgs.User" user "User.Drawings")
		(19 "Cmts.User" user "User.Comments")
		(21 "Eco1.User" user "User.Eco1")
		(23 "Eco2.User" user "User.Eco2")
		(25 "Edge.Cuts" user)
		(27 "Margin" user)
		(31 "F.CrtYd" user "F.Courtyard")
		(29 "B.CrtYd" user "B.Courtyard")
		(35 "F.Fab" user)
		(33 "B.Fab" user)
	)
	(footprint "antmicro-footprints:R_0402_1005Metric"
		(layer "F.Cu")
		(at 106.467962 139.1665 180)
		(descr "Resistor SMD 0402")
		(tags "resistor SMD 0402")
		(property "Reference" "R924"
			(at -1.38 0.83 0)
			(layer "F.SilkS")
			(effects
				(font
					(size 0.7 0.7)
					(thickness 0.15)
				)
				(justify right bottom)
			)
		)
		(property "Value" "R_10k_0402"
			(at -1.011843 1.772047 0)
			(layer "F.Fab")
			(effects
				(font
					(size 0.7 0.7)
					(thickness 0.15)
				)
				(justify right bottom)
			)
		)
		(property "Datasheet" "https://www.bourns.com/docs/product-datasheets/cr.pdf"
			(at 0 0 180)
			(layer "F.Fab")
			(hide yes)
			(effects
				(font
					(size 1.27 1.27)
					(thickness 0.15)
				)
			)
		)
		(property "Manufacturer" "Bourns"
			(at 0 0 180)
			(unlocked yes)
			(layer "F.Fab")
			(hide yes)
			(effects
				(font
					(size 1 1)
					(thickness 0.15)
				)
			)
		)
		(property "MPN" "CR0402-FX-1002GLF"
			(at 0 0 180)
			(unlocked yes)
			(layer "F.Fab")
			(hide yes)
			(effects
				(font
					(size 1 1)
					(thickness 0.15)
				)
			)
		)
		(property "Val" "10k"
			(at 0 0 180)
			(unlocked yes)
			(layer "F.Fab")
			(hide yes)
			(effects
				(font
					(size 1 1)
					(thickness 0.15)
				)
			)
		)
		(property "License" "Apache-2.0"
			(at 0 0 180)
			(unlocked yes)
			(layer "F.Fab")
			(hide yes)
			(effects
				(font
					(size 1 1)
					(thickness 0.15)
				)
			)
		)
		(property "Author" "Antmicro"
			(at 0 0 180)
			(unlocked yes)
			(layer "F.Fab")
			(hide yes)
			(effects
				(font
					(size 1 1)
					(thickness 0.15)
				)
			)
		)
		(property "Tolerance" "1%"
			(at 0 0 180)
			(unlocked yes)
			(layer "F.Fab")
			(hide yes)
			(effects
				(font
					(size 1 1)
					(thickness 0.15)
				)
			)
		)
		(sheetname "/USB/")
		(sheetfile "usb.kicad_sch")
		(attr smd)
		(fp_rect
			(start -0.925 -0.47)
			(end 0.925 0.47)
			(stroke
				(width 0.05)
				(type default)
			)
			(fill no)
			(layer "F.CrtYd")
		)
		(fp_rect
			(start -0.5 -0.25)
			(end 0.5 0.25)
			(stroke
				(width 0.15)
				(type solid)
			)
			(fill no)
			(layer "F.Fab")
		)
		(fp_text user "${REFERENCE}"
			(at -0.95 3.168 180)
			(layer "F.Fab")
			(effects
				(font
					(size 0.7 0.7)
					(thickness 0.15)
				)
				(justify left bottom)
			)
		)
		(fp_text user "Author: Antmicro"
			(at -0.95 4.169 180)
			(layer "F.Fab")
			(effects
				(font
					(size 0.7 0.7)
					(thickness 0.15)
				)
				(justify left bottom)
			)
		)
		(fp_text user "License: Apache-2.0"
			(at -0.95 5.169 180)
			(layer "F.Fab")
			(effects
				(font
					(size 0.7 0.7)
					(thickness 0.15)
				)
				(justify left bottom)
			)
		)
		(pad "1" smd roundrect
			(at -0.48 0 180)
			(size 0.59 0.64)
			(layers "F.Cu" "F.Mask" "F.Paste")
			(roundrect_rratio 0.25)
			(net 9 "+3V3")
			(pintype "passive")
		)
		(pad "2" smd roundrect
			(at 0.48 0 180)
			(size 0.59 0.64)
			(layers "F.Cu" "F.Mask" "F.Paste")
			(roundrect_rratio 0.25)
			(net 279 "/Compute module/USB.OTGID")
			(pintype "passive")
		)
	)
	(footprint "antmicro-footprints:R_0402_1005Metric"
		(layer "F.Cu")
		(at 129.267962 119.6165)
		(descr "Resistor SMD 0402")
		(tags "resistor SMD 0402")
		(property "Reference" "R213"
			(at -3.7 0.12 0)
			(layer "F.SilkS")
			(effects
				(font
					(size 0.7 0.7)
					(thickness 0.15)
				)
				(justify left bottom)
			)
		)
		(property "Value" "R_100k_0402"
			(at -1.011843 1.772047 0)
			(layer "F.Fab")
			(effects
				(font
					(size 0.7 0.7)
					(thickness 0.15)
				)
				(justify left bottom)
			)
		)
		(property "Datasheet" "https://www.bourns.com/docs/product-datasheets/cr.pdf"
			(at 0 0 0)
			(layer "F.Fab")
			(hide yes)
			(effects
				(font
					(size 1.27 1.27)
					(thickness 0.15)
				)
			)
		)
		(property "Manufacturer" "Bourns"
			(at 0 0 0)
			(unlocked yes)
			(layer "F.Fab")
			(hide yes)
			(effects
				(font
					(size 1 1)
					(thickness 0.15)
				)
			)
		)
		(property "MPN" "CR0402-FX-1003GLF"
			(at 0 0 0)
			(unlocked yes)
			(layer "F.Fab")
			(hide yes)
			(effects
				(font
					(size 1 1)
					(thickness 0.15)
				)
			)
		)
		(property "Val" "100k"
			(at 0 0 0)
			(unlocked yes)
			(layer "F.Fab")
			(hide yes)
			(effects
				(font
					(size 1 1)
					(thickness 0.15)
				)
			)
		)
		(property "License" "Apache-2.0"
			(at 0 0 0)
			(unlocked yes)
			(layer "F.Fab")
			(hide yes)
			(effects
				(font
					(size 1 1)
					(thickness 0.15)
				)
			)
		)
		(property "Author" "Antmicro"
			(at 0 0 0)
			(unlocked yes)
			(layer "F.Fab")
			(hide yes)
			(effects
				(font
					(size 1 1)
					(thickness 0.15)
				)
			)
		)
		(property "Tolerance" "1%"
			(at 0 0 0)
			(unlocked yes)
			(layer "F.Fab")
			(hide yes)
			(effects
				(font
					(size 1 1)
					(thickness 0.15)
				)
			)
		)
		(sheetname "/Compute module/")
		(sheetfile "compute-module.kicad_sch")
		(attr smd)
		(fp_rect
			(start -0.925 -0.47)
			(end 0.925 0.47)
			(stroke
				(width 0.05)
				(type default)
			)
			(fill no)
			(layer "F.CrtYd")
		)
		(fp_rect
			(start -0.5 -0.25)
			(end 0.5 0.25)
			(stroke
				(width 0.15)
				(type solid)
			)
			(fill no)
			(layer "F.Fab")
		)
		(fp_text user "${REFERENCE}"
			(at -0.95 3.168 0)
			(layer "F.Fab")
			(effects
				(font
					(size 0.7 0.7)
					(thickness 0.15)
				)
				(justify left bottom)
			)
		)
		(fp_text user "License: Apache-2.0"
			(at -0.95 5.169 0)
			(layer "F.Fab")
			(effects
				(font
					(size 0.7 0.7)
					(thickness 0.15)
				)
				(justify left bottom)
			)
		)
		(fp_text user "Author: Antmicro"
			(at -0.95 4.169 0)
			(layer "F.Fab")
			(effects
				(font
					(size 0.7 0.7)
					(thickness 0.15)
				)
				(justify left bottom)
			)
		)
		(pad "1" smd roundrect
			(at -0.48 0)
			(size 0.59 0.64)
			(layers "F.Cu" "F.Mask" "F.Paste")
			(roundrect_rratio 0.25)
			(net 3 "GND")
			(pintype "passive")
		)
		(pad "2" smd roundrect
			(at 0.48 0)
			(size 0.59 0.64)
			(layers "F.Cu" "F.Mask" "F.Paste")
			(roundrect_rratio 0.25)
			(net 4 "Net-(D204-A)")
			(pintype "passive")
		)
	)
	(footprint "antmicro-footprints:Nexperia_DFN-10_2.5x1mm_P0.5mm"
		(layer "F.Cu")
		(at 134.079962 144.1785 90)
		(property "Reference" "D809"
			(at -1.298 -1.562 90)
			(layer "F.SilkS")
			(effects
				(font
					(size 0.7 0.7)
					(thickness 0.15)
				)
				(justify left bottom)
			)
		)
		(property "Value" "PUSB3F96X_PASS"
			(at -0.016 1.705 90)
			(layer "F.Fab")
			(effects
				(font
					(size 0.7 0.7)
					(thickness 0.15)
				)
				(justify left bottom)
			)
		)
		(property "Datasheet" "https://mouser.com/datasheet/2/916/PUSB3F96-1600324.pdf"
			(at 0 0 90)
			(layer "F.Fab")
			(hide yes)
			(effects
				(font
					(size 1.27 1.27)
					(thickness 0.15)
				)
			)
		)
		(property "Manufacturer" "Nexperia"
			(at 0 0 90)
			(unlocked yes)
			(layer "F.Fab")
			(hide yes)
			(effects
				(font
					(size 1 1)
					(thickness 0.15)
				)
			)
		)
		(property "MPN" "PUSB3F96X"
			(at 0 0 90)
			(unlocked yes)
			(layer "F.Fab")
			(hide yes)
			(effects
				(font
					(size 1 1)
					(thickness 0.15)
				)
			)
		)
		(property "Author" "Antmicro"
			(at 0 0 90)
			(unlocked yes)
			(layer "F.Fab")
			(hide yes)
			(effects
				(font
					(size 1 1)
					(thickness 0.15)
				)
			)
		)
		(property "License" "Apache-2.0"
			(at 0 0 90)
			(unlocked yes)
			(layer "F.Fab")
			(hide yes)
			(effects
				(font
					(size 1 1)
					(thickness 0.15)
				)
			)
		)
		(sheetname "/Peripherals/")
		(sheetfile "peripherals.kicad_sch")
		(attr smd)
		(fp_line
			(start -1.375 -0.4)
			(end -1.375 0.4)
			(stroke
				(width 0.15)
				(type solid)
			)
			(layer "F.SilkS")
		)
		(fp_line
			(start 1.375 0.4)
			(end 1.375 -0.4)
			(stroke
				(width 0.15)
				(type solid)
			)
			(layer "F.SilkS")
		)
		(fp_circle
			(center -1.4 0.7)
			(end -1.349 0.7)
			(stroke
				(width 0.15)
				(type solid)
			)
			(fill yes)
			(layer "F.SilkS")
		)
		(fp_rect
			(start -1.4 -0.725)
			(end 1.4 0.725)
			(stroke
				(width 0.05)
				(type solid)
			)
			(fill no)
			(layer "F.CrtYd")
		)
		(fp_line
			(start 1.25 -0.5)
			(end -1.25 -0.5)
			(stroke
				(width 0.15)
				(type solid)
			)
			(layer "F.Fab")
		)
		(fp_line
			(start -1.25 -0.5)
			(end -1.25 0.15)
			(stroke
				(width 0.15)
				(type solid)
			)
			(layer "F.Fab")
		)
		(fp_line
			(start -1.25 0.15)
			(end -0.9 0.5)
			(stroke
				(width 0.15)
				(type solid)
			)
			(layer "F.Fab")
		)
		(fp_line
			(start 1.25 0.5)
			(end 1.25 -0.5)
			(stroke
				(width 0.15)
				(type solid)
			)
			(layer "F.Fab")
		)
		(fp_line
			(start -0.9 0.5)
			(end 1.25 0.5)
			(stroke
				(width 0.15)
				(type solid)
			)
			(layer "F.Fab")
		)
		(fp_text user "Author: Antmicro"
			(at -1.367 4.905 90)
			(layer "F.Fab")
			(effects
				(font
					(size 0.7 0.7)
					(thickness 0.15)
				)
				(justify left bottom)
			)
		)
		(fp_text user "${REFERENCE}"
			(at -1.367 3.704 90)
			(layer "F.Fab")
			(effects
				(font
					(size 0.7 0.7)
					(thickness 0.15)
				)
				(justify left bottom)
			)
		)
		(fp_text user "License: Apache-2.0"
			(at -1.367 6.105 90)
			(layer "F.Fab")
			(effects
				(font
					(size 0.7 0.7)
					(thickness 0.15)
				)
				(justify left bottom)
			)
		)
		(pad "1" smd rect
			(at -1 0.3875 90)
			(size 0.2 0.475)
			(layers "F.Cu" "F.Mask" "F.Paste")
			(net 228 "/Compute module/GPIO.8{slash}TXD4")
			(pinfunction "CH1")
			(pintype "passive")
			(solder_mask_margin 0.05)
		)
		(pad "2" smd rect
			(at -0.5 0.3875 90)
			(size 0.2 0.475)
			(layers "F.Cu" "F.Mask" "F.Paste")
			(net 226 "/Compute module/GPIO.7")
			(pinfunction "CH2")
			(pintype "passive")
			(solder_mask_margin 0.05)
		)
		(pad "3" smd rect
			(at 0 0.3875 90)
			(size 0.2 0.475)
			(layers "F.Cu" "F.Mask" "F.Paste")
			(net 3 "GND")
			(pinfunction "GND")
			(pintype "passive")
			(solder_mask_margin 0.05)
		)
		(pad "4" smd rect
			(at 0.5 0.3875 90)
			(size 0.2 0.475)
			(layers "F.Cu" "F.Mask" "F.Paste")
			(net 446 "/Compute module/GPIO.1{slash}SCL0")
			(pinfunction "CH3")
			(pintype "passive")
			(solder_mask_margin 0.05)
		)
		(pad "5" smd rect
			(at 1 0.3875 90)
			(size 0.2 0.475)
			(layers "F.Cu" "F.Mask" "F.Paste")
			(net 253 "/Compute module/GPIO.AIN0")
			(pinfunction "CH4")
			(pintype "passive")
			(solder_mask_margin 0.05)
		)
		(pad "6" smd rect
			(at 1 -0.3875 90)
			(size 0.2 0.475)
			(layers "F.Cu" "F.Mask" "F.Paste")
			(net 253 "/Compute module/GPIO.AIN0")
			(pinfunction "CH4")
			(pintype "passive")
			(solder_mask_margin 0.05)
		)
		(pad "7" smd rect
			(at 0.5 -0.3875 90)
			(size 0.2 0.475)
			(layers "F.Cu" "F.Mask" "F.Paste")
			(net 446 "/Compute module/GPIO.1{slash}SCL0")
			(pinfunction "CH3")
			(pintype "passive")
			(solder_mask_margin 0.05)
		)
		(pad "8" smd rect
			(at 0 -0.3875 90)
			(size 0.2 0.475)
			(layers "F.Cu" "F.Mask" "F.Paste")
			(net 3 "GND")
			(pinfunction "GND")
			(pintype "passive")
			(solder_mask_margin 0.05)
		)
		(pad "9" smd rect
			(at -0.501 -0.3875 90)
			(size 0.2 0.475)
			(layers "F.Cu" "F.Mask" "F.Paste")
			(net 226 "/Compute module/GPIO.7")
			(pinfunction "CH2")
			(pintype "passive")
			(solder_mask_margin 0.05)
		)
		(pad "10" smd rect
			(at -1 -0.3875 90)
			(size 0.2 0.475)
			(layers "F.Cu" "F.Mask" "F.Paste")
			(net 228 "/Compute module/GPIO.8{slash}TXD4")
			(pinfunction "CH1")
			(pintype "passive")
			(solder_mask_margin 0.05)
		)
	)
	(footprint "antmicro-footprints:C_0402_1005Metric"
		(layer "F.Cu")
		(at 94.092962 148.7915)
		(descr "Capacitor SMD 0402")
		(tags "capacitor SMD 0402")
		(property "Reference" "C210"
			(at 2.025 0.425 0)
			(layer "F.SilkS")
			(effects
				(font
					(size 0.7 0.7)
					(thickness 0.15)
				)
				(justify left bottom)
			)
		)
		(property "Value" "C_100n_0402"
			(at -1.022927 2.155213 0)
			(layer "F.Fab")
			(effects
				(font
					(size 0.7 0.7)
					(thickness 0.15)
				)
				(justify left bottom)
			)
		)
		(property "Datasheet" "https://www.murata.com/products/productdetail?partno=GRM155R61H104KE14%23"
			(at 0 0 0)
			(layer "F.Fab")
			(hide yes)
			(effects
				(font
					(size 1.27 1.27)
					(thickness 0.15)
				)
			)
		)
		(property "Manufacturer" "Murata"
			(at 0 0 0)
			(unlocked yes)
			(layer "F.Fab")
			(hide yes)
			(effects
				(font
					(size 1 1)
					(thickness 0.15)
				)
			)
		)
		(property "MPN" "GRM155R61H104KE14D"
			(at 0 0 0)
			(unlocked yes)
			(layer "F.Fab")
			(hide yes)
			(effects
				(font
					(size 1 1)
					(thickness 0.15)
				)
			)
		)
		(property "Val" "100n"
			(at 0 0 0)
			(unlocked yes)
			(layer "F.Fab")
			(hide yes)
			(effects
				(font
					(size 1 1)
					(thickness 0.15)
				)
			)
		)
		(property "License" "Apache-2.0"
			(at 0 0 0)
			(unlocked yes)
			(layer "F.Fab")
			(hide yes)
			(effects
				(font
					(size 1 1)
					(thickness 0.15)
				)
			)
		)
		(property "Author" "Antmicro"
			(at 0 0 0)
			(unlocked yes)
			(layer "F.Fab")
			(hide yes)
			(effects
				(font
					(size 1 1)
					(thickness 0.15)
				)
			)
		)
		(property "Voltage" "50V"
			(at 0 0 0)
			(unlocked yes)
			(layer "F.Fab")
			(hide yes)
			(effects
				(font
					(size 1 1)
					(thickness 0.15)
				)
			)
		)
		(property "Dielectric" "X5R"
			(at 0 0 0)
			(unlocked yes)
			(layer "F.Fab")
			(hide yes)
			(effects
				(font
					(size 1 1)
					(thickness 0.15)
				)
			)
		)
		(sheetname "/Compute module/")
		(sheetfile "compute-module.kicad_sch")
		(attr smd)
		(fp_rect
			(start -0.925 -0.47)
			(end 0.925 0.47)
			(stroke
				(width 0.05)
				(type default)
			)
			(fill no)
			(layer "F.CrtYd")
		)
		(fp_line
			(start -0.494 -0.25)
			(end 0.504 -0.25)
			(stroke
				(width 0.15)
				(type solid)
			)
			(layer "F.Fab")
		)
		(fp_line
			(start -0.494 0.248)
			(end -0.494 -0.25)
			(stroke
				(width 0.15)
				(type solid)
			)
			(layer "F.Fab")
		)
		(fp_line
			(start 0.504 -0.25)
			(end 0.504 0.248)
			(stroke
				(width 0.15)
				(type solid)
			)
			(layer "F.Fab")
		)
		(fp_line
			(start 0.504 0.248)
			(end -0.494 0.248)
			(stroke
				(width 0.15)
				(type solid)
			)
			(layer "F.Fab")
		)
		(fp_text user "License: Apache-2.0"
			(at -0.939 5.799 0)
			(layer "F.Fab")
			(effects
				(font
					(size 0.7 0.7)
					(thickness 0.15)
				)
				(justify left bottom)
			)
		)
		(fp_text user "${REFERENCE}"
			(at -0.939 4.599 0)
			(layer "F.Fab")
			(effects
				(font
					(size 0.7 0.7)
					(thickness 0.15)
				)
				(justify left bottom)
			)
		)
		(fp_text user "Author: Antmicro"
			(at -0.939 3.399 0)
			(layer "F.Fab")
			(effects
				(font
					(size 0.7 0.7)
					(thickness 0.15)
				)
				(justify left bottom)
			)
		)
		(pad "1" smd roundrect
			(at -0.48 0)
			(size 0.59 0.64)
			(layers "F.Cu" "F.Mask" "F.Paste")
			(roundrect_rratio 0.25)
			(net 3 "GND")
			(pintype "passive")
		)
		(pad "2" smd roundrect
			(at 0.48 0)
			(size 0.59 0.64)
			(layers "F.Cu" "F.Mask" "F.Paste")
			(roundrect_rratio 0.25)
			(net 9 "+3V3")
			(pintype "passive")
		)
	)
	(footprint "antmicro-footprints:TP_SMD_0.75mm"
		(layer "F.Cu")
		(at 109.467962 153.5665)
		(property "Reference" "TP214"
			(at -0.617962 -0.5165 180)
			(layer "F.SilkS")
			(effects
				(font
					(size 0.7 0.7)
					(thickness 0.15)
				)
				(justify left bottom)
			)
		)
		(property "Value" "TP_0.75mm_SMD"
			(at 0 1.2 0)
			(layer "F.Fab")
			(effects
				(font
					(size 0.7 0.7)
					(thickness 0.15)
				)
				(justify left bottom)
			)
		)
		(property "MPN" ""
			(at 0 0 0)
			(unlocked yes)
			(layer "F.Fab")
			(hide yes)
			(effects
				(font
					(size 1 1)
					(thickness 0.15)
				)
			)
		)
		(property "Manufacturer" ""
			(at 0 0 0)
			(unlocked yes)
			(layer "F.Fab")
			(hide yes)
			(effects
				(font
					(size 1 1)
					(thickness 0.15)
				)
			)
		)
		(property "Author" "Antmicro"
			(at 0 0 0)
			(unlocked yes)
			(layer "F.Fab")
			(hide yes)
			(effects
				(font
					(size 1 1)
					(thickness 0.15)
				)
			)
		)
		(property "License" "Apache-2.0"
			(at 0 0 0)
			(unlocked yes)
			(layer "F.Fab")
			(hide yes)
			(effects
				(font
					(size 1 1)
					(thickness 0.15)
				)
			)
		)
		(sheetname "/Compute module/")
		(sheetfile "compute-module.kicad_sch")
		(attr exclude_from_pos_files exclude_from_bom)
		(fp_circle
			(center 0 0)
			(end 0.475 0)
			(stroke
				(width 0.05)
				(type default)
			)
			(fill no)
			(layer "F.CrtYd")
		)
		(fp_text user "License: Apache-2.0"
			(at -0.4 5.101 0)
			(layer "F.Fab")
			(effects
				(font
					(size 0.7 0.7)
					(thickness 0.15)
				)
				(justify left bottom)
			)
		)
		(fp_text user "${REFERENCE}"
			(at -0.4 2.7 0)
			(layer "F.Fab")
			(effects
				(font
					(size 0.7 0.7)
					(thickness 0.15)
				)
				(justify left bottom)
			)
		)
		(fp_text user "Author: Antmicro"
			(at -0.4 3.901 0)
			(layer "F.Fab")
			(effects
				(font
					(size 0.7 0.7)
					(thickness 0.15)
				)
				(justify left bottom)
			)
		)
		(pad "1" smd circle
			(at 0 0)
			(size 0.75 0.75)
			(layers "F.Cu" "F.Mask")
			(net 257 "/Compute module/Pf_5V.HPD")
			(pinfunction "1")
			(pintype "passive")
		)
	)
)
